# T6G (Grand Teton) — schematic netlist excerpt (pin names and nets, part order shuffled) for the footprints in the layout excerpt that follows; sources: Cadence DE-HDL packaged netlist, KiCad conversion of 04192023_DAF0TMB3IC0_F0TG_MB_C_brd_V02_OCP.brd

R2205  Q_RES  2.2K 5% EMPTY  pkg 0402LF  page 250 : A = P3V3_AUX ; B = SMB_PCIE0_3V3AUX_SDA
R6041  Q_RES  100K 1% CHIP  pkg 0402LF  page 167 : A = GND ; B = FPGA_DEBUG_LED_CTRL

(kicad_pcb
	(version 20260206)
	(generator "pcbnew")
	(generator_version "10.0")
	(general
		(thickness 1.6)
		(legacy_teardrops no)
	)
	(paper "A4")
	(title_block
		(title "04192023_DAF0TMB3IC0_F0TG_MB_C_brd_V02_OCP.brd")
		(comment 1 "Grand Teton / footprints 7197-7198 of 8354")
	)
	(layers
		(0 "F.Cu" signal "TOP")
		(4 "In1.Cu" signal "GND")
		(6 "In2.Cu" signal "IN1")
		(8 "In3.Cu" signal "GND1")
		(10 "In4.Cu" signal "IN2")
		(12 "In5.Cu" signal "GND2")
		(14 "In6.Cu" signal "IN3")
		(16 "In7.Cu" signal "GND3")
		(18 "In8.Cu" signal "VCC")
		(20 "In9.Cu" signal "VCC1")
		(22 "In10.Cu" signal "GND4")
		(24 "In11.Cu" signal "IN4")
		(26 "In12.Cu" signal "GND5")
		(28 "In13.Cu" signal "IN5")
		(30 "In14.Cu" signal "GND6")
		(32 "In15.Cu" signal "IN6")
		(34 "In16.Cu" signal "GND7")
		(2 "B.Cu" signal "BOTTOM")
		(9 "F.Adhes" user "F.Adhesive")
		(11 "B.Adhes" user "B.Adhesive")
		(13 "F.Paste" user "Package Geometry/Pastemask Top")
		(15 "B.Paste" user "Package Geometry/Pastemask Bottom")
		(5 "F.SilkS" user "Ref Des/Silkscreen Top")
		(7 "B.SilkS" user "Ref Des/Silkscreen Bottom")
		(1 "F.Mask" user "Board Geometry/Soldermask Top")
		(3 "B.Mask" user "Board Geometry/Soldermask Bottom")
		(17 "Dwgs.User" user "User.Drawings")
		(19 "Cmts.User" user "User.Comments")
		(21 "Eco1.User" user "User.Eco1")
		(23 "Eco2.User" user "User.Eco2")
		(25 "Edge.Cuts" user "Board Geometry/Outline")
		(27 "Margin" user)
		(31 "F.CrtYd" user "Package Geometry/Place Bound Top")
		(29 "B.CrtYd" user "Package Geometry/Place Bound Bottom")
		(35 "F.Fab" user "Ref Des/Assembly Top")
		(33 "B.Fab" user "Ref Des/Assembly Bottom")
	)
	(footprint ""
		(layer "B.Cu")
		(at 428.98695 -30.165548 180)
		(property "Reference" "R6041"
			(at 0 0 0)
			(layer "B.SilkS")
			(hide yes)
			(effects
				(font
					(size 1.27 1.27)
				)
				(justify mirror)
			)
		)
		(property "Value" ""
			(at 0 0 0)
			(layer "B.Fab")
			(effects
				(font
					(size 1.27 1.27)
				)
				(justify mirror)
			)
		)
		(duplicate_pad_numbers_are_jumpers no)
		(fp_line
			(start 0.7874 0.4064)
			(end 0.7874 -0.4064)
			(stroke
				(width 0.1524)
				(type default)
			)
			(layer "B.SilkS")
		)
		(fp_line
			(start 0.7874 -0.4064)
			(end -0.7874 -0.4064)
			(stroke
				(width 0.1524)
				(type default)
			)
			(layer "B.SilkS")
		)
		(fp_line
			(start -0.7874 0.4064)
			(end 0.7874 0.4064)
			(stroke
				(width 0.1524)
				(type default)
			)
			(layer "B.SilkS")
		)
		(fp_line
			(start -0.7874 -0.4064)
			(end -0.7874 0.4064)
			(stroke
				(width 0.1524)
				(type default)
			)
			(layer "B.SilkS")
		)
		(fp_line
			(start 0.67945 0.3048)
			(end 0.67945 -0.305054)
			(stroke
				(width 0.1)
				(type default)
			)
			(layer "B.Fab")
		)
		(fp_line
			(start 0.67945 -0.305054)
			(end 0.12065 -0.305054)
			(stroke
				(width 0.1)
				(type default)
			)
			(layer "B.Fab")
		)
		(fp_line
			(start 0.12065 0.3048)
			(end 0.67945 0.3048)
			(stroke
				(width 0.1)
				(type default)
			)
			(layer "B.Fab")
		)
		(fp_line
			(start 0.12065 0.2794)
			(end 0.12065 0.3048)
			(stroke
				(width 0.1)
				(type default)
			)
			(layer "B.Fab")
		)
		(fp_line
			(start 0.12065 -0.2794)
			(end -0.12065 -0.2794)
			(stroke
				(width 0.1)
				(type default)
			)
			(layer "B.Fab")
		)
		(fp_line
			(start 0.12065 -0.305054)
			(end 0.12065 -0.2794)
			(stroke
				(width 0.1)
				(type default)
			)
			(layer "B.Fab")
		)
		(fp_line
			(start -0.120396 0.3048)
			(end -0.120396 0.2794)
			(stroke
				(width 0.1)
				(type default)
			)
			(layer "B.Fab")
		)
		(fp_line
			(start -0.120396 0.2794)
			(end 0.12065 0.2794)
			(stroke
				(width 0.1)
				(type default)
			)
			(layer "B.Fab")
		)
		(fp_line
			(start -0.12065 -0.2794)
			(end -0.12065 -0.3048)
			(stroke
				(width 0.1)
				(type default)
			)
			(layer "B.Fab")
		)
		(fp_line
			(start -0.12065 -0.3048)
			(end -0.67945 -0.3048)
			(stroke
				(width 0.1)
				(type default)
			)
			(layer "B.Fab")
		)
		(fp_line
			(start -0.67945 0.3048)
			(end -0.120396 0.3048)
			(stroke
				(width 0.1)
				(type default)
			)
			(layer "B.Fab")
		)
		(fp_line
			(start -0.67945 -0.3048)
			(end -0.67945 0.3048)
			(stroke
				(width 0.1)
				(type default)
			)
			(layer "B.Fab")
		)
		(pad "1" smd circle
			(at 0.40005 0)
			(size 0 0)
			(layers "B.Cu" "B.Mask" "B.Paste")
			(net "GND")
		)
		(pad "2" smd circle
			(at -0.40005 0)
			(size 0 0)
			(layers "B.Cu" "B.Mask" "B.Paste")
			(net "FPGA_DEBUG_LED_CTRL")
		)
	)
	(footprint ""
		(layer "B.Cu")
		(at 163.359084 -9.013444 -90)
		(property "Reference" "R2205"
			(at 0 0 90)
			(layer "B.SilkS")
			(hide yes)
			(effects
				(font
					(size 1.27 1.27)
				)
				(justify mirror)
			)
		)
		(property "Value" ""
			(at 0 0 90)
			(layer "B.Fab")
			(effects
				(font
					(size 1.27 1.27)
				)
				(justify mirror)
			)
		)
		(duplicate_pad_numbers_are_jumpers no)
		(fp_line
			(start -0.7874 0.4064)
			(end 0.7874 0.4064)
			(stroke
				(width 0.1524)
				(type default)
			)
			(layer "B.SilkS")
		)
		(fp_line
			(start 0.7874 0.4064)
			(end 0.7874 -0.4064)
			(stroke
				(width 0.1524)
				(type default)
			)
			(layer "B.SilkS")
		)
		(fp_line
			(start -0.7874 -0.4064)
			(end -0.7874 0.4064)
			(stroke
				(width 0.1524)
				(type default)
			)
			(layer "B.SilkS")
		)
		(fp_line
			(start 0.7874 -0.4064)
			(end -0.7874 -0.4064)
			(stroke
				(width 0.1524)
				(type default)
			)
			(layer "B.SilkS")
		)
		(fp_line
			(start -0.67945 0.3048)
			(end -0.120396 0.3048)
			(stroke
				(width 0.1)
				(type default)
			)
			(layer "B.Fab")
		)
		(fp_line
			(start -0.120396 0.3048)
			(end -0.120396 0.2794)
			(stroke
				(width 0.1)
				(type default)
			)
			(layer "B.Fab")
		)
		(fp_line
			(start 0.12065 0.3048)
			(end 0.67945 0.3048)
			(stroke
				(width 0.1)
				(type default)
			)
			(layer "B.Fab")
		)
		(fp_line
			(start 0.67945 0.3048)
			(end 0.67945 -0.305054)
			(stroke
				(width 0.1)
				(type default)
			)
			(layer "B.Fab")
		)
		(fp_line
			(start -0.120396 0.2794)
			(end 0.12065 0.2794)
			(stroke
				(width 0.1)
				(type default)
			)
			(layer "B.Fab")
		)
		(fp_line
			(start 0.12065 0.2794)
			(end 0.12065 0.3048)
			(stroke
				(width 0.1)
				(type default)
			)
			(layer "B.Fab")
		)
		(fp_line
			(start -0.12065 -0.2794)
			(end -0.12065 -0.3048)
			(stroke
				(width 0.1)
				(type default)
			)
			(layer "B.Fab")
		)
		(fp_line
			(start 0.12065 -0.2794)
			(end -0.12065 -0.2794)
			(stroke
				(width 0.1)
				(type default)
			)
			(layer "B.Fab")
		)
		(fp_line
			(start -0.67945 -0.3048)
			(end -0.67945 0.3048)
			(stroke
				(width 0.1)
				(type default)
			)
			(layer "B.Fab")
		)
		(fp_line
			(start -0.12065 -0.3048)
			(end -0.67945 -0.3048)
			(stroke
				(width 0.1)
				(type default)
			)
			(layer "B.Fab")
		)
		(fp_line
			(start 0.12065 -0.305054)
			(end 0.12065 -0.2794)
			(stroke
				(width 0.1)
				(type default)
			)
			(layer "B.Fab")
		)
		(fp_line
			(start 0.67945 -0.305054)
			(end 0.12065 -0.305054)
			(stroke
				(width 0.1)
				(type default)
			)
			(layer "B.Fab")
		)
		(pad "1" smd circle
			(at 0.40005 0 90)
			(size 0 0)
			(layers "B.Cu" "B.Mask" "B.Paste")
			(net "P3V3_AUX")
		)
		(pad "2" smd circle
			(at -0.40005 0 90)
			(size 0 0)
			(layers "B.Cu" "B.Mask" "B.Paste")
			(net "SMB_PCIE0_3V3AUX_SDA")
		)
	)
)
